(kicad_pcb
	(version 20260206)
	(generator "pcbnew")
	(generator_version "10.0")
	(general
		(thickness 1.6)
		(legacy_teardrops no)
	)
	(paper "A4")
	(title_block
		(title "panther-plus-userver — 13130-1b_20150205.brd")
		(comment 1 "Honey Badger (Wiwynn) / footprints 26-33 of 1509")
	)
	(layers
		(0 "F.Cu" signal "TOP")
		(4 "In1.Cu" signal "L2")
		(6 "In2.Cu" signal "L3")
		(8 "In3.Cu" signal "L4")
		(10 "In4.Cu" signal "L5")
		(12 "In5.Cu" signal "L6")
		(14 "In6.Cu" signal "L7")
		(16 "In7.Cu" signal "L8")
		(18 "In8.Cu" signal "L9")
		(20 "In9.Cu" signal "L10")
		(22 "In10.Cu" signal "L11")
		(2 "B.Cu" signal "BOTTOM")
		(9 "F.Adhes" user "F.Adhesive")
		(11 "B.Adhes" user "B.Adhesive")
		(13 "F.Paste" user "Package Geometry/Pastemask Top")
		(15 "B.Paste" user "Package Geometry/Pastemask Bottom")
		(5 "F.SilkS" user "Ref Des/Silkscreen Top")
		(7 "B.SilkS" user "Ref Des/Silkscreen Bottom")
		(1 "F.Mask" user "Board Geometry/Soldermask Top")
		(3 "B.Mask" user "Board Geometry/Soldermask Bottom")
		(17 "Dwgs.User" user "User.Drawings")
		(19 "Cmts.User" user "User.Comments")
		(21 "Eco1.User" user "User.Eco1")
		(23 "Eco2.User" user "User.Eco2")
		(25 "Edge.Cuts" user "Board Geometry/Outline")
		(27 "Margin" user)
		(31 "F.CrtYd" user "Package Geometry/Place Bound Top")
		(29 "B.CrtYd" user "Package Geometry/Place Bound Bottom")
		(35 "F.Fab" user "Ref Des/Assembly Top")
		(33 "B.Fab" user "Ref Des/Assembly Bottom")
	)
	(footprint ""
		(layer "F.Cu")
		(at 107.569 -20.701 90)
		(property "Reference" "R170"
			(at 0 0 90)
			(layer "F.SilkS")
			(hide yes)
			(effects
				(font
					(size 1.27 1.27)
				)
			)
		)
		(property "Value" "1KR2F-3-GP"
			(at 0.064008 -3.993896 90)
			(unlocked yes)
			(layer "F.Fab")
			(hide yes)
			(effects
				(font
					(size 1.016 1.016)
					(thickness 0.1524)
				)
			)
		)
		(property "Device Type" "R402H16"
			(at 0.064008 -5.517896 90)
			(unlocked yes)
			(layer "F.Fab")
			(hide yes)
			(effects
				(font
					(size 1.016 1.016)
					(thickness 0.1524)
				)
			)
		)
		(duplicate_pad_numbers_are_jumpers no)
		(fp_rect
			(start -0.381 0.8382)
			(end 0.381 -0.8382)
			(stroke
				(width 0)
				(type default)
			)
			(fill no)
			(layer "F.CrtYd")
		)
		(fp_rect
			(start -0.381 0.8382)
			(end 0.381 -0.8382)
			(stroke
				(width 0)
				(type default)
			)
			(fill no)
			(layer "F.Fab")
		)
		(pad "1" smd custom
			(at 0 -0.4318 90)
			(size 0.127 0.127)
			(layers "F.Cu" "F.Mask" "F.Paste")
			(net "PV_VDDR")
			(options
				(clearance outline)
				(anchor circle)
			)
			(primitives
				(gr_poly
					(pts
						(arc
							(start -0.2032 -0.2794)
							(mid -0.239121 -0.264521)
							(end -0.254 -0.2286)
						)
						(arc
							(start -0.254 0.2286)
							(mid -0.239121 0.264521)
							(end -0.2032 0.2794)
						)
						(arc
							(start 0.2032 0.2794)
							(mid 0.239121 0.264521)
							(end 0.254 0.2286)
						)
						(arc
							(start 0.254 -0.2286)
							(mid 0.239121 -0.264521)
							(end 0.2032 -0.2794)
						)
					)
					(width 0)
					(fill yes)
				)
			)
		)
		(pad "2" smd custom
			(at 0 0.4318 90)
			(size 0.127 0.127)
			(layers "F.Cu" "F.Mask" "F.Paste")
			(net "M_B_RESET#")
			(options
				(clearance outline)
				(anchor circle)
			)
			(primitives
				(gr_poly
					(pts
						(arc
							(start -0.2032 -0.2794)
							(mid -0.239121 -0.264521)
							(end -0.254 -0.2286)
						)
						(arc
							(start -0.254 0.2286)
							(mid -0.239121 0.264521)
							(end -0.2032 0.2794)
						)
						(arc
							(start 0.2032 0.2794)
							(mid 0.239121 0.264521)
							(end 0.254 0.2286)
						)
						(arc
							(start 0.254 -0.2286)
							(mid 0.239121 -0.264521)
							(end 0.2032 -0.2794)
						)
					)
					(width 0)
					(fill yes)
				)
			)
		)
	)
	(footprint ""
		(layer "F.Cu")
		(at 91.186 -13.208)
		(property "Reference" "R459"
			(at 0 0 0)
			(layer "F.SilkS")
			(hide yes)
			(effects
				(font
					(size 1.27 1.27)
				)
			)
		)
		(property "Value" "4K7R2F-GP"
			(at 1.7907 -1.1176 0)
			(unlocked yes)
			(layer "F.Fab")
			(hide yes)
			(effects
				(font
					(size 1.016 1.016)
					(thickness 0.1524)
				)
			)
		)
		(property "Device Type" "R402H16"
			(at 1.7907 -2.6416 0)
			(unlocked yes)
			(layer "F.Fab")
			(hide yes)
			(effects
				(font
					(size 1.016 1.016)
					(thickness 0.1524)
				)
			)
		)
		(duplicate_pad_numbers_are_jumpers no)
		(fp_rect
			(start -0.381 0.8382)
			(end 0.381 -0.8382)
			(stroke
				(width 0)
				(type default)
			)
			(fill no)
			(layer "F.CrtYd")
		)
		(fp_rect
			(start -0.381 0.8382)
			(end 0.381 -0.8382)
			(stroke
				(width 0)
				(type default)
			)
			(fill no)
			(layer "F.Fab")
		)
		(pad "1" smd custom
			(at 0 -0.4318)
			(size 0.127 0.127)
			(layers "F.Cu" "F.Mask" "F.Paste")
			(net "P3V3_STBY")
			(options
				(clearance outline)
				(anchor circle)
			)
			(primitives
				(gr_poly
					(pts
						(arc
							(start -0.2032 -0.2794)
							(mid -0.239121 -0.264521)
							(end -0.254 -0.2286)
						)
						(arc
							(start -0.254 0.2286)
							(mid -0.239121 0.264521)
							(end -0.2032 0.2794)
						)
						(arc
							(start 0.2032 0.2794)
							(mid 0.239121 0.264521)
							(end 0.254 0.2286)
						)
						(arc
							(start 0.254 -0.2286)
							(mid 0.239121 -0.264521)
							(end 0.2032 -0.2794)
						)
					)
					(width 0)
					(fill yes)
				)
			)
		)
		(pad "2" smd custom
			(at 0 0.4318)
			(size 0.127 0.127)
			(layers "F.Cu" "F.Mask" "F.Paste")
			(net "SLOT_ID3")
			(options
				(clearance outline)
				(anchor circle)
			)
			(primitives
				(gr_poly
					(pts
						(arc
							(start -0.2032 -0.2794)
							(mid -0.239121 -0.264521)
							(end -0.254 -0.2286)
						)
						(arc
							(start -0.254 0.2286)
							(mid -0.239121 0.264521)
							(end -0.2032 0.2794)
						)
						(arc
							(start 0.2032 0.2794)
							(mid 0.239121 0.264521)
							(end 0.254 0.2286)
						)
						(arc
							(start 0.254 -0.2286)
							(mid 0.239121 -0.264521)
							(end 0.2032 -0.2794)
						)
					)
					(width 0)
					(fill yes)
				)
			)
		)
	)
	(footprint ""
		(layer "F.Cu")
		(at 68.072 -51.054 -90)
		(property "Reference" "R465"
			(at 0 0 270)
			(layer "F.SilkS")
			(hide yes)
			(effects
				(font
					(size 1.27 1.27)
				)
			)
		)
		(property "Value" "4K7R2F-GP"
			(at 1.7907 -1.1176 270)
			(unlocked yes)
			(layer "F.Fab")
			(hide yes)
			(effects
				(font
					(size 1.016 1.016)
					(thickness 0.1524)
				)
			)
		)
		(property "Device Type" "R402H16"
			(at 1.7907 -2.6416 270)
			(unlocked yes)
			(layer "F.Fab")
			(hide yes)
			(effects
				(font
					(size 1.016 1.016)
					(thickness 0.1524)
				)
			)
		)
		(duplicate_pad_numbers_are_jumpers no)
		(fp_rect
			(start -0.381 0.8382)
			(end 0.381 -0.8382)
			(stroke
				(width 0)
				(type default)
			)
			(fill no)
			(layer "F.CrtYd")
		)
		(fp_rect
			(start -0.381 0.8382)
			(end 0.381 -0.8382)
			(stroke
				(width 0)
				(type default)
			)
			(fill no)
			(layer "F.Fab")
		)
		(pad "1" smd custom
			(at 0 -0.4318 270)
			(size 0.127 0.127)
			(layers "F.Cu" "F.Mask" "F.Paste")
			(net "P3V3")
			(options
				(clearance outline)
				(anchor circle)
			)
			(primitives
				(gr_poly
					(pts
						(arc
							(start -0.2032 -0.2794)
							(mid -0.239121 -0.264521)
							(end -0.254 -0.2286)
						)
						(arc
							(start -0.254 0.2286)
							(mid -0.239121 0.264521)
							(end -0.2032 0.2794)
						)
						(arc
							(start 0.2032 0.2794)
							(mid 0.239121 0.264521)
							(end 0.254 0.2286)
						)
						(arc
							(start 0.254 -0.2286)
							(mid 0.239121 -0.264521)
							(end 0.2032 -0.2794)
						)
					)
					(width 0)
					(fill yes)
				)
			)
		)
		(pad "2" smd custom
			(at 0 0.4318 270)
			(size 0.127 0.127)
			(layers "F.Cu" "F.Mask" "F.Paste")
			(net "SMBUS_SW_INV_D")
			(options
				(clearance outline)
				(anchor circle)
			)
			(primitives
				(gr_poly
					(pts
						(arc
							(start -0.2032 -0.2794)
							(mid -0.239121 -0.264521)
							(end -0.254 -0.2286)
						)
						(arc
							(start -0.254 0.2286)
							(mid -0.239121 0.264521)
							(end -0.2032 0.2794)
						)
						(arc
							(start 0.2032 0.2794)
							(mid 0.239121 0.264521)
							(end 0.254 0.2286)
						)
						(arc
							(start 0.254 -0.2286)
							(mid 0.239121 -0.264521)
							(end 0.2032 -0.2794)
						)
					)
					(width 0)
					(fill yes)
				)
			)
		)
	)
	(footprint ""
		(layer "F.Cu")
		(at 186.436 -39.878)
		(property "Reference" "PR123"
			(at 0 0 0)
			(layer "F.SilkS")
			(hide yes)
			(effects
				(font
					(size 1.27 1.27)
				)
			)
		)
		(property "Value" "0R2J-2-GP"
			(at 1.7907 -1.1176 0)
			(unlocked yes)
			(layer "F.Fab")
			(hide yes)
			(effects
				(font
					(size 1.016 1.016)
					(thickness 0.1524)
				)
			)
		)
		(property "Device Type" "R402H16"
			(at 1.7907 -2.6416 0)
			(unlocked yes)
			(layer "F.Fab")
			(hide yes)
			(effects
				(font
					(size 1.016 1.016)
					(thickness 0.1524)
				)
			)
		)
		(duplicate_pad_numbers_are_jumpers no)
		(fp_rect
			(start -0.381 0.8382)
			(end 0.381 -0.8382)
			(stroke
				(width 0)
				(type default)
			)
			(fill no)
			(layer "F.CrtYd")
		)
		(fp_rect
			(start -0.381 0.8382)
			(end 0.381 -0.8382)
			(stroke
				(width 0)
				(type default)
			)
			(fill no)
			(layer "F.Fab")
		)
		(pad "1" smd custom
			(at 0 -0.4318)
			(size 0.127 0.127)
			(layers "F.Cu" "F.Mask" "F.Paste")
			(net "GND")
			(options
				(clearance outline)
				(anchor circle)
			)
			(primitives
				(gr_poly
					(pts
						(arc
							(start -0.2032 -0.2794)
							(mid -0.239121 -0.264521)
							(end -0.254 -0.2286)
						)
						(arc
							(start -0.254 0.2286)
							(mid -0.239121 0.264521)
							(end -0.2032 0.2794)
						)
						(arc
							(start 0.2032 0.2794)
							(mid 0.239121 0.264521)
							(end 0.254 0.2286)
						)
						(arc
							(start 0.254 -0.2286)
							(mid 0.239121 -0.264521)
							(end 0.2032 -0.2794)
						)
					)
					(width 0)
					(fill yes)
				)
			)
		)
		(pad "2" smd custom
			(at 0 0.4318)
			(size 0.127 0.127)
			(layers "F.Cu" "F.Mask" "F.Paste")
			(net "VR_PVDDR_A_IAUTO")
			(options
				(clearance outline)
				(anchor circle)
			)
			(primitives
				(gr_poly
					(pts
						(arc
							(start -0.2032 -0.2794)
							(mid -0.239121 -0.264521)
							(end -0.254 -0.2286)
						)
						(arc
							(start -0.254 0.2286)
							(mid -0.239121 0.264521)
							(end -0.2032 0.2794)
						)
						(arc
							(start 0.2032 0.2794)
							(mid 0.239121 0.264521)
							(end 0.254 0.2286)
						)
						(arc
							(start 0.254 -0.2286)
							(mid 0.239121 -0.264521)
							(end 0.2032 -0.2794)
						)
					)
					(width 0)
					(fill yes)
				)
			)
		)
	)
	(footprint ""
		(layer "F.Cu")
		(at 73.66 -49.276)
		(property "Reference" "R44"
			(at 0 0 0)
			(layer "F.SilkS")
			(hide yes)
			(effects
				(font
					(size 1.27 1.27)
				)
			)
		)
		(property "Value" "4K7R2F-GP"
			(at 0.064008 -3.993896 0)
			(unlocked yes)
			(layer "F.Fab")
			(hide yes)
			(effects
				(font
					(size 1.016 1.016)
					(thickness 0.1524)
				)
			)
		)
		(property "Device Type" "R402H16"
			(at 0.064008 -5.517896 0)
			(unlocked yes)
			(layer "F.Fab")
			(hide yes)
			(effects
				(font
					(size 1.016 1.016)
					(thickness 0.1524)
				)
			)
		)
		(duplicate_pad_numbers_are_jumpers no)
		(fp_rect
			(start -0.381 0.8382)
			(end 0.381 -0.8382)
			(stroke
				(width 0)
				(type default)
			)
			(fill no)
			(layer "F.CrtYd")
		)
		(fp_rect
			(start -0.381 0.8382)
			(end 0.381 -0.8382)
			(stroke
				(width 0)
				(type default)
			)
			(fill no)
			(layer "F.Fab")
		)
		(pad "1" smd custom
			(at 0 -0.4318)
			(size 0.127 0.127)
			(layers "F.Cu" "F.Mask" "F.Paste")
			(net "P3V3")
			(options
				(clearance outline)
				(anchor circle)
			)
			(primitives
				(gr_poly
					(pts
						(arc
							(start -0.2032 -0.2794)
							(mid -0.239121 -0.264521)
							(end -0.254 -0.2286)
						)
						(arc
							(start -0.254 0.2286)
							(mid -0.239121 0.264521)
							(end -0.2032 0.2794)
						)
						(arc
							(start 0.2032 0.2794)
							(mid 0.239121 0.264521)
							(end 0.254 0.2286)
						)
						(arc
							(start 0.254 -0.2286)
							(mid 0.239121 -0.264521)
							(end 0.2032 -0.2794)
						)
					)
					(width 0)
					(fill yes)
				)
			)
		)
		(pad "2" smd custom
			(at 0 0.4318)
			(size 0.127 0.127)
			(layers "F.Cu" "F.Mask" "F.Paste")
			(net "BD_ID_0")
			(options
				(clearance outline)
				(anchor circle)
			)
			(primitives
				(gr_poly
					(pts
						(arc
							(start -0.2032 -0.2794)
							(mid -0.239121 -0.264521)
							(end -0.254 -0.2286)
						)
						(arc
							(start -0.254 0.2286)
							(mid -0.239121 0.264521)
							(end -0.2032 0.2794)
						)
						(arc
							(start 0.2032 0.2794)
							(mid 0.239121 0.264521)
							(end 0.254 0.2286)
						)
						(arc
							(start 0.254 -0.2286)
							(mid 0.239121 -0.264521)
							(end 0.2032 -0.2794)
						)
					)
					(width 0)
					(fill yes)
				)
			)
		)
	)
	(footprint ""
		(layer "F.Cu")
		(at 50.1142 -34.925 180)
		(property "Reference" "R105"
			(at 0 0 180)
			(layer "F.SilkS")
			(hide yes)
			(effects
				(font
					(size 1.27 1.27)
				)
			)
		)
		(property "Value" "4K7R2F-GP"
			(at 0.064008 -3.993896 180)
			(unlocked yes)
			(layer "F.Fab")
			(hide yes)
			(effects
				(font
					(size 1.016 1.016)
					(thickness 0.1524)
				)
			)
		)
		(property "Device Type" "R402H16"
			(at 0.064008 -5.517896 180)
			(unlocked yes)
			(layer "F.Fab")
			(hide yes)
			(effects
				(font
					(size 1.016 1.016)
					(thickness 0.1524)
				)
			)
		)
		(duplicate_pad_numbers_are_jumpers no)
		(fp_rect
			(start -0.381 0.8382)
			(end 0.381 -0.8382)
			(stroke
				(width 0)
				(type default)
			)
			(fill no)
			(layer "F.CrtYd")
		)
		(fp_rect
			(start -0.381 0.8382)
			(end 0.381 -0.8382)
			(stroke
				(width 0)
				(type default)
			)
			(fill no)
			(layer "F.Fab")
		)
		(pad "1" smd custom
			(at 0 -0.4318 180)
			(size 0.127 0.127)
			(layers "F.Cu" "F.Mask" "F.Paste")
			(net "SPI_HOLD#")
			(options
				(clearance outline)
				(anchor circle)
			)
			(primitives
				(gr_poly
					(pts
						(arc
							(start -0.2032 -0.2794)
							(mid -0.239121 -0.264521)
							(end -0.254 -0.2286)
						)
						(arc
							(start -0.254 0.2286)
							(mid -0.239121 0.264521)
							(end -0.2032 0.2794)
						)
						(arc
							(start 0.2032 0.2794)
							(mid 0.239121 0.264521)
							(end 0.254 0.2286)
						)
						(arc
							(start 0.254 -0.2286)
							(mid 0.239121 -0.264521)
							(end 0.2032 -0.2794)
						)
					)
					(width 0)
					(fill yes)
				)
			)
		)
		(pad "2" smd custom
			(at 0 0.4318 180)
			(size 0.127 0.127)
			(layers "F.Cu" "F.Mask" "F.Paste")
			(net "P3V3_CPU")
			(options
				(clearance outline)
				(anchor circle)
			)
			(primitives
				(gr_poly
					(pts
						(arc
							(start -0.2032 -0.2794)
							(mid -0.239121 -0.264521)
							(end -0.254 -0.2286)
						)
						(arc
							(start -0.254 0.2286)
							(mid -0.239121 0.264521)
							(end -0.2032 0.2794)
						)
						(arc
							(start 0.2032 0.2794)
							(mid 0.239121 0.264521)
							(end 0.254 0.2286)
						)
						(arc
							(start 0.254 -0.2286)
							(mid 0.239121 -0.264521)
							(end 0.2032 -0.2794)
						)
					)
					(width 0)
					(fill yes)
				)
			)
		)
	)
	(footprint ""
		(layer "F.Cu")
		(at 41.148 -58.039 90)
		(property "Reference" "PU2"
			(at 0 0 90)
			(layer "F.SilkS")
			(hide yes)
			(effects
				(font
					(size 1.27 1.27)
				)
			)
		)
		(property "Value" "IRFH4253DTRPBF-GP-U"
			(at -3.9116 -4.5085 90)
			(unlocked yes)
			(layer "F.Fab")
			(hide yes)
			(effects
				(font
					(size 1.016 1.016)
					(thickness 0.1524)
				)
			)
		)
		(property "Device Type" "DFN8A5060-G2PH40"
			(at -3.9116 -6.0325 90)
			(unlocked yes)
			(layer "F.Fab")
			(hide yes)
			(effects
				(font
					(size 1.016 1.016)
					(thickness 0.1524)
				)
			)
		)
		(duplicate_pad_numbers_are_jumpers no)
		(fp_rect
			(start -2.7559 3.3782)
			(end 2.7559 -3.3782)
			(stroke
				(width 0)
				(type default)
			)
			(fill no)
			(layer "F.CrtYd")
		)
		(fp_rect
			(start -2.7559 3.3782)
			(end 2.7559 -3.3782)
			(stroke
				(width 0)
				(type default)
			)
			(fill no)
			(layer "F.Fab")
		)
		(pad "1" smd rect
			(at 1.905 -2.796794 90)
			(size 0.6604 0.9144)
			(layers "F.Cu" "F.Mask" "F.Paste")
			(net "VR_PVCCP_GH_R")
		)
		(pad "2" smd rect
			(at 0.635 -2.796794 90)
			(size 0.6604 0.9144)
			(layers "F.Cu" "F.Mask" "F.Paste")
			(net "VR_PVCCP_PHASE")
		)
		(pad "3" smd rect
			(at -0.635 -2.796794 90)
			(size 0.6604 0.9144)
			(layers "F.Cu" "F.Mask" "F.Paste")
			(net "VR_FET_SW_P12V_PVCCP_PVNN")
		)
		(pad "4" smd rect
			(at -1.905 -2.796794 90)
			(size 0.6604 0.9144)
			(layers "F.Cu" "F.Mask" "F.Paste")
			(net "VR_FET_SW_P12V_PVCCP_PVNN")
		)
		(pad "5" smd rect
			(at -1.905 2.745994 90)
			(size 0.6604 1.016)
			(layers "F.Cu" "F.Mask" "F.Paste")
			(net "VR_PVCCP_PWM_OUT")
		)
		(pad "6" smd rect
			(at -0.635 2.745994 90)
			(size 0.6604 1.016)
			(layers "F.Cu" "F.Mask" "F.Paste")
			(net "VR_PVCCP_PWM_OUT")
		)
		(pad "7" smd rect
			(at 0.635 2.745994 90)
			(size 0.6604 1.016)
			(layers "F.Cu" "F.Mask" "F.Paste")
			(net "VR_PVCCP_PWM_OUT")
		)
		(pad "8" smd rect
			(at 1.905 2.174494 90)
			(size 0.6604 2.159)
			(layers "F.Cu" "F.Mask" "F.Paste")
			(net "VR_PVCCP_LH_R")
		)
		(pad "9" smd custom
			(at 0 0.635 90)
			(size 0.66675 0.66675)
			(layers "F.Cu" "F.Mask" "F.Paste")
			(net "GND")
			(options
				(clearance outline)
				(anchor circle)
			)
			(primitives
				(gr_poly
					(pts
						(xy -2.3241 1.3335) (xy -2.3241 -1.3335) (xy 2.3241 -1.3335) (xy 2.3241 0.1905) (xy 1.1049 0.1905)
						(xy 1.1049 1.3335)
					)
					(width 0)
					(fill yes)
				)
			)
		)
		(pad "10" smd rect
			(at 0 -1.59512 90)
			(size 4.2672 1.0414)
			(layers "F.Cu" "F.Mask" "F.Paste")
			(net "VR_FET_SW_P12V_PVCCP_PVNN")
		)
	)
	(footprint ""
		(layer "F.Cu")
		(at 47.6504 -37.5158)
		(property "Reference" "C28"
			(at 0 0 0)
			(layer "F.SilkS")
			(hide yes)
			(effects
				(font
					(size 1.27 1.27)
				)
			)
		)
		(property "Value" "SCD1U10V2KX-5GP"
			(at 1.8923 -1.2065 0)
			(unlocked yes)
			(layer "F.Fab")
			(hide yes)
			(effects
				(font
					(size 1.016 1.016)
					(thickness 0.1524)
				)
			)
		)
		(property "Device Type" "C402H22"
			(at 1.8923 -2.7305 0)
			(unlocked yes)
			(layer "F.Fab")
			(hide yes)
			(effects
				(font
					(size 1.016 1.016)
					(thickness 0.1524)
				)
			)
		)
		(duplicate_pad_numbers_are_jumpers no)
		(fp_rect
			(start -0.381 0.7366)
			(end 0.381 -0.7366)
			(stroke
				(width 0)
				(type default)
			)
			(fill no)
			(layer "F.CrtYd")
		)
		(fp_rect
			(start -0.381 0.7366)
			(end 0.381 -0.7366)
			(stroke
				(width 0)
				(type default)
			)
			(fill no)
			(layer "F.Fab")
		)
		(pad "1" smd custom
			(at 0 -0.4572)
			(size 0.1143 0.1143)
			(layers "F.Cu" "F.Mask" "F.Paste")
			(net "P3V3_STBY")
			(options
				(clearance outline)
				(anchor circle)
			)
			(primitives
				(gr_poly
					(pts
						(arc
							(start -0.254 -0.1778)
							(mid -0.239121 -0.213721)
							(end -0.2032 -0.2286)
						)
						(arc
							(start 0.2032 -0.2286)
							(mid 0.239121 -0.213721)
							(end 0.254 -0.1778)
						)
						(arc
							(start 0.254 0.1778)
							(mid 0.239121 0.213721)
							(end 0.2032 0.2286)
						)
						(arc
							(start -0.2032 0.2286)
							(mid -0.239121 0.213721)
							(end -0.254 0.1778)
						)
					)
					(width 0)
					(fill yes)
				)
			)
		)
		(pad "2" smd custom
			(at 0 0.4572)
			(size 0.1143 0.1143)
			(layers "F.Cu" "F.Mask" "F.Paste")
			(net "GND")
			(options
				(clearance outline)
				(anchor circle)
			)
			(primitives
				(gr_poly
					(pts
						(arc
							(start -0.254 -0.1778)
							(mid -0.239121 -0.213721)
							(end -0.2032 -0.2286)
						)
						(arc
							(start 0.2032 -0.2286)
							(mid 0.239121 -0.213721)
							(end 0.254 -0.1778)
						)
						(arc
							(start 0.254 0.1778)
							(mid 0.239121 0.213721)
							(end 0.2032 0.2286)
						)
						(arc
							(start -0.2032 0.2286)
							(mid -0.239121 0.213721)
							(end -0.254 0.1778)
						)
					)
					(width 0)
					(fill yes)
				)
			)
		)
	)
)
